(kicad_pcb
	(version 20260206)
	(generator "pcbnew")
	(generator_version "10.0")
	(general
		(thickness 1.6)
		(legacy_teardrops no)
	)
	(paper "A4")
	(title_block
		(title "01162023_DA0F0TEBIF0_F0T_Expander_BD_F_brd_V02_OCP.brd")
		(comment 1 "Grand Teton / footprint 6619 of 9728 (PEX0), pads 1535-1651 of 2397")
	)
	(layers
		(0 "F.Cu" signal "TOP")
		(4 "In1.Cu" signal "GND")
		(6 "In2.Cu" signal "VCC")
		(8 "In3.Cu" signal "VCC1")
		(10 "In4.Cu" signal "GND1")
		(12 "In5.Cu" signal "IN1")
		(14 "In6.Cu" signal "GND2")
		(16 "In7.Cu" signal "IN2")
		(18 "In8.Cu" signal "GND3")
		(20 "In9.Cu" signal "IN3")
		(22 "In10.Cu" signal "GND4")
		(24 "In11.Cu" signal "IN4")
		(26 "In12.Cu" signal "GND5")
		(28 "In13.Cu" signal "IN5")
		(30 "In14.Cu" signal "GND6")
		(32 "In15.Cu" signal "IN6")
		(34 "In16.Cu" signal "GND7")
		(2 "B.Cu" signal "BOTTOM")
		(9 "F.Adhes" user "F.Adhesive")
		(11 "B.Adhes" user "B.Adhesive")
		(13 "F.Paste" user "Package Geometry/Pastemask Top")
		(15 "B.Paste" user "Package Geometry/Pastemask Bottom")
		(5 "F.SilkS" user "Ref Des/Silkscreen Top")
		(7 "B.SilkS" user "Ref Des/Silkscreen Bottom")
		(1 "F.Mask" user "Board Geometry/Soldermask Top")
		(3 "B.Mask" user "Board Geometry/Soldermask Bottom")
		(17 "Dwgs.User" user "User.Drawings")
		(19 "Cmts.User" user "User.Comments")
		(21 "Eco1.User" user "User.Eco1")
		(23 "Eco2.User" user "User.Eco2")
		(25 "Edge.Cuts" user "Board Geometry/Outline")
		(27 "Margin" user)
		(31 "F.CrtYd" user "Package Geometry/Place Bound Top")
		(29 "B.CrtYd" user "Package Geometry/Place Bound Bottom")
		(35 "F.Fab" user "Ref Des/Assembly Top")
		(33 "B.Fab" user "Ref Des/Assembly Bottom")
	)
	(footprint ""
		(layer "F.Cu")
		(at 59.649868 -295.89984)
		(property "Reference" "PEX0"
			(at -3.360166 35.566858 0)
			(unlocked yes)
			(layer "F.SilkS")
			(effects
				(font
					(size 2.032 1.524)
					(thickness 0.1524)
				)
				(justify left)
			)
		)
		(property "Value" ""
			(at 0 0 0)
			(layer "F.Fab")
			(effects
				(font
					(size 1.27 1.27)
				)
			)
		)
		(duplicate_pad_numbers_are_jumpers no)
		(pad "C20" smd circle
			(at -4.750054 -20.899882)
			(size 0.4572 0.4572)
			(layers "F.Cu" "F.Mask" "F.Paste")
			(net "P5E_PEX0_STN6_RX_DN<99>")
		)
		(pad "C21" smd circle
			(at -3.800094 -20.899882)
			(size 0.4572 0.4572)
			(layers "F.Cu" "F.Mask" "F.Paste")
			(net "GND")
		)
		(pad "C22" smd circle
			(at -2.84988 -20.899882)
			(size 0.4572 0.4572)
			(layers "F.Cu" "F.Mask" "F.Paste")
			(net "P5E_PEX0_STN6_RX_DN<97>")
		)
		(pad "C23" smd circle
			(at -1.89992 -20.899882)
			(size 0.4572 0.4572)
			(layers "F.Cu" "F.Mask" "F.Paste")
			(net "GND")
		)
		(pad "C24" smd circle
			(at -0.94996 -20.899882)
			(size 0.4572 0.4572)
			(layers "F.Cu" "F.Mask" "F.Paste")
			(net "P5E_PEX0_STN5_RX_DN<80>")
		)
		(pad "C25" smd circle
			(at 0 -20.899882)
			(size 0.4572 0.4572)
			(layers "F.Cu" "F.Mask" "F.Paste")
			(net "GND")
		)
		(pad "C26" smd circle
			(at 0.94996 -20.899882)
			(size 0.4572 0.4572)
			(layers "F.Cu" "F.Mask" "F.Paste")
			(net "P5E_PEX0_STN5_RX_DN<82>")
		)
		(pad "C27" smd circle
			(at 1.89992 -20.899882)
			(size 0.4572 0.4572)
			(layers "F.Cu" "F.Mask" "F.Paste")
			(net "GND")
		)
		(pad "C28" smd circle
			(at 2.84988 -20.899882)
			(size 0.4572 0.4572)
			(layers "F.Cu" "F.Mask" "F.Paste")
			(net "P5E_PEX0_STN5_RX_DN<84>")
		)
		(pad "C29" smd circle
			(at 3.800094 -20.899882)
			(size 0.4572 0.4572)
			(layers "F.Cu" "F.Mask" "F.Paste")
			(net "GND")
		)
		(pad "C30" smd circle
			(at 4.750054 -20.899882)
			(size 0.4572 0.4572)
			(layers "F.Cu" "F.Mask" "F.Paste")
			(net "P5E_PEX0_STN5_RX_DN<86>")
		)
		(pad "C31" smd circle
			(at 5.700014 -20.899882)
			(size 0.4572 0.4572)
			(layers "F.Cu" "F.Mask" "F.Paste")
			(net "GND")
		)
		(pad "C32" smd circle
			(at 6.649974 -20.899882)
			(size 0.4572 0.4572)
			(layers "F.Cu" "F.Mask" "F.Paste")
			(net "P5E_PEX0_STN5_RX_DN<88>")
		)
		(pad "C33" smd circle
			(at 7.599934 -20.899882)
			(size 0.4572 0.4572)
			(layers "F.Cu" "F.Mask" "F.Paste")
			(net "GND")
		)
		(pad "C34" smd circle
			(at 8.549894 -20.899882)
			(size 0.4572 0.4572)
			(layers "F.Cu" "F.Mask" "F.Paste")
			(net "P5E_PEX0_STN5_RX_DN<90>")
		)
		(pad "C35" smd circle
			(at 9.500108 -20.899882)
			(size 0.4572 0.4572)
			(layers "F.Cu" "F.Mask" "F.Paste")
			(net "GND")
		)
		(pad "C36" smd circle
			(at 10.450068 -20.899882)
			(size 0.4572 0.4572)
			(layers "F.Cu" "F.Mask" "F.Paste")
			(net "P5E_PEX0_STN5_RX_DN<92>")
		)
		(pad "C37" smd circle
			(at 11.400028 -20.899882)
			(size 0.4572 0.4572)
			(layers "F.Cu" "F.Mask" "F.Paste")
			(net "GND")
		)
		(pad "C38" smd circle
			(at 12.349988 -20.899882)
			(size 0.4572 0.4572)
			(layers "F.Cu" "F.Mask" "F.Paste")
			(net "P5E_PEX0_STN5_RX_DN<94>")
		)
		(pad "C39" smd circle
			(at 13.299948 -20.899882)
			(size 0.4572 0.4572)
			(layers "F.Cu" "F.Mask" "F.Paste")
			(net "GND")
		)
		(pad "C40" smd circle
			(at 14.249908 -20.899882)
			(size 0.4572 0.4572)
			(layers "F.Cu" "F.Mask" "F.Paste")
			(net "P5E_PEX0_STN4_RX_DN<79>")
		)
		(pad "C41" smd circle
			(at 15.200122 -20.899882)
			(size 0.4572 0.4572)
			(layers "F.Cu" "F.Mask" "F.Paste")
			(net "GND")
		)
		(pad "C42" smd circle
			(at 16.150082 -20.899882)
			(size 0.4572 0.4572)
			(layers "F.Cu" "F.Mask" "F.Paste")
			(net "P5E_PEX0_STN4_RX_DN<77>")
		)
		(pad "C43" smd circle
			(at 17.100042 -20.899882)
			(size 0.4572 0.4572)
			(layers "F.Cu" "F.Mask" "F.Paste")
			(net "GND")
		)
		(pad "C44" smd circle
			(at 18.050002 -20.899882)
			(size 0.4572 0.4572)
			(layers "F.Cu" "F.Mask" "F.Paste")
			(net "P5E_PEX0_STN4_RX_DN<75>")
		)
		(pad "C45" smd circle
			(at 18.999962 -20.899882)
			(size 0.4572 0.4572)
			(layers "F.Cu" "F.Mask" "F.Paste")
			(net "GND")
		)
		(pad "C46" smd circle
			(at 19.949922 -20.899882)
			(size 0.4572 0.4572)
			(layers "F.Cu" "F.Mask" "F.Paste")
			(net "P5E_PEX0_STN4_RX_DN<73>")
		)
		(pad "C47" smd circle
			(at 20.899882 -20.899882)
			(size 0.4572 0.4572)
			(layers "F.Cu" "F.Mask" "F.Paste")
			(net "GND")
		)
		(pad "C48" smd circle
			(at 21.850096 -20.899882)
			(size 0.4572 0.4572)
			(layers "F.Cu" "F.Mask" "F.Paste")
			(net "P5E_PEX0_STN4_RX_DP<71>")
		)
		(pad "C49" smd circle
			(at 22.800056 -20.899882)
			(size 0.4572 0.4572)
			(layers "F.Cu" "F.Mask" "F.Paste")
			(net "P5E_PEX0_STN4_RX_DN<71>")
		)
		(pad "D1" smd circle
			(at -22.800056 -19.949922)
			(size 0.4572 0.4572)
			(layers "F.Cu" "F.Mask" "F.Paste")
			(net "GND")
		)
		(pad "D2" smd circle
			(at -21.850096 -19.949922)
			(size 0.4572 0.4572)
			(layers "F.Cu" "F.Mask" "F.Paste")
			(net "GND")
		)
		(pad "D3" smd circle
			(at -20.899882 -19.949922)
			(size 0.4572 0.4572)
			(layers "F.Cu" "F.Mask" "F.Paste")
			(net "GND")
		)
		(pad "D4" smd circle
			(at -19.949922 -19.949922)
			(size 0.4572 0.4572)
			(layers "F.Cu" "F.Mask" "F.Paste")
			(net "P5E_PEX0_STN7_RX_DP<124>")
		)
		(pad "D5" smd circle
			(at -18.999962 -19.949922)
			(size 0.4572 0.4572)
			(layers "F.Cu" "F.Mask" "F.Paste")
			(net "GND")
		)
		(pad "D6" smd circle
			(at -18.050002 -19.949922)
			(size 0.4572 0.4572)
			(layers "F.Cu" "F.Mask" "F.Paste")
			(net "P5E_PEX0_STN7_RX_DP<126>")
		)
		(pad "D7" smd circle
			(at -17.100042 -19.949922)
			(size 0.4572 0.4572)
			(layers "F.Cu" "F.Mask" "F.Paste")
			(net "GND")
		)
		(pad "D8" smd circle
			(at -16.150082 -19.949922)
			(size 0.4572 0.4572)
			(layers "F.Cu" "F.Mask" "F.Paste")
			(net "P5E_PEX0_STN6_RX_DP<111>")
		)
		(pad "D9" smd circle
			(at -15.200122 -19.949922)
			(size 0.4572 0.4572)
			(layers "F.Cu" "F.Mask" "F.Paste")
			(net "GND")
		)
		(pad "D10" smd circle
			(at -14.249908 -19.949922)
			(size 0.4572 0.4572)
			(layers "F.Cu" "F.Mask" "F.Paste")
			(net "P5E_PEX0_STN6_RX_DP<109>")
		)
		(pad "D11" smd circle
			(at -13.299948 -19.949922)
			(size 0.4572 0.4572)
			(layers "F.Cu" "F.Mask" "F.Paste")
			(net "GND")
		)
		(pad "D12" smd circle
			(at -12.349988 -19.949922)
			(size 0.4572 0.4572)
			(layers "F.Cu" "F.Mask" "F.Paste")
			(net "P5E_PEX0_STN6_RX_DP<107>")
		)
		(pad "D13" smd circle
			(at -11.400028 -19.949922)
			(size 0.4572 0.4572)
			(layers "F.Cu" "F.Mask" "F.Paste")
			(net "GND")
		)
		(pad "D14" smd circle
			(at -10.450068 -19.949922)
			(size 0.4572 0.4572)
			(layers "F.Cu" "F.Mask" "F.Paste")
			(net "P5E_PEX0_STN6_RX_DP<105>")
		)
		(pad "D15" smd circle
			(at -9.500108 -19.949922)
			(size 0.4572 0.4572)
			(layers "F.Cu" "F.Mask" "F.Paste")
			(net "GND")
		)
		(pad "D16" smd circle
			(at -8.549894 -19.949922)
			(size 0.4572 0.4572)
			(layers "F.Cu" "F.Mask" "F.Paste")
			(net "P5E_PEX0_STN6_RX_DP<103>")
		)
		(pad "D17" smd circle
			(at -7.599934 -19.949922)
			(size 0.4572 0.4572)
			(layers "F.Cu" "F.Mask" "F.Paste")
			(net "GND")
		)
		(pad "D18" smd circle
			(at -6.649974 -19.949922)
			(size 0.4572 0.4572)
			(layers "F.Cu" "F.Mask" "F.Paste")
			(net "P5E_PEX0_STN6_RX_DP<101>")
		)
		(pad "D19" smd circle
			(at -5.700014 -19.949922)
			(size 0.4572 0.4572)
			(layers "F.Cu" "F.Mask" "F.Paste")
			(net "GND")
		)
		(pad "D20" smd circle
			(at -4.750054 -19.949922)
			(size 0.4572 0.4572)
			(layers "F.Cu" "F.Mask" "F.Paste")
			(net "P5E_PEX0_STN6_RX_DP<99>")
		)
		(pad "D21" smd circle
			(at -3.800094 -19.949922)
			(size 0.4572 0.4572)
			(layers "F.Cu" "F.Mask" "F.Paste")
			(net "GND")
		)
		(pad "D22" smd circle
			(at -2.84988 -19.949922)
			(size 0.4572 0.4572)
			(layers "F.Cu" "F.Mask" "F.Paste")
			(net "P5E_PEX0_STN6_RX_DP<97>")
		)
		(pad "D23" smd circle
			(at -1.89992 -19.949922)
			(size 0.4572 0.4572)
			(layers "F.Cu" "F.Mask" "F.Paste")
			(net "GND")
		)
		(pad "D24" smd circle
			(at -0.94996 -19.949922)
			(size 0.4572 0.4572)
			(layers "F.Cu" "F.Mask" "F.Paste")
			(net "P5E_PEX0_STN5_RX_DP<80>")
		)
		(pad "D25" smd circle
			(at 0 -19.949922)
			(size 0.4572 0.4572)
			(layers "F.Cu" "F.Mask" "F.Paste")
			(net "GND")
		)
		(pad "D26" smd circle
			(at 0.94996 -19.949922)
			(size 0.4572 0.4572)
			(layers "F.Cu" "F.Mask" "F.Paste")
			(net "P5E_PEX0_STN5_RX_DP<82>")
		)
		(pad "D27" smd circle
			(at 1.89992 -19.949922)
			(size 0.4572 0.4572)
			(layers "F.Cu" "F.Mask" "F.Paste")
			(net "GND")
		)
		(pad "D28" smd circle
			(at 2.84988 -19.949922)
			(size 0.4572 0.4572)
			(layers "F.Cu" "F.Mask" "F.Paste")
			(net "P5E_PEX0_STN5_RX_DP<84>")
		)
		(pad "D29" smd circle
			(at 3.800094 -19.949922)
			(size 0.4572 0.4572)
			(layers "F.Cu" "F.Mask" "F.Paste")
			(net "GND")
		)
		(pad "D30" smd circle
			(at 4.750054 -19.949922)
			(size 0.4572 0.4572)
			(layers "F.Cu" "F.Mask" "F.Paste")
			(net "P5E_PEX0_STN5_RX_DP<86>")
		)
		(pad "D31" smd circle
			(at 5.700014 -19.949922)
			(size 0.4572 0.4572)
			(layers "F.Cu" "F.Mask" "F.Paste")
			(net "GND")
		)
		(pad "D32" smd circle
			(at 6.649974 -19.949922)
			(size 0.4572 0.4572)
			(layers "F.Cu" "F.Mask" "F.Paste")
			(net "P5E_PEX0_STN5_RX_DP<88>")
		)
		(pad "D33" smd circle
			(at 7.599934 -19.949922)
			(size 0.4572 0.4572)
			(layers "F.Cu" "F.Mask" "F.Paste")
			(net "GND")
		)
		(pad "D34" smd circle
			(at 8.549894 -19.949922)
			(size 0.4572 0.4572)
			(layers "F.Cu" "F.Mask" "F.Paste")
			(net "P5E_PEX0_STN5_RX_DP<90>")
		)
		(pad "D35" smd circle
			(at 9.500108 -19.949922)
			(size 0.4572 0.4572)
			(layers "F.Cu" "F.Mask" "F.Paste")
			(net "GND")
		)
		(pad "D36" smd circle
			(at 10.450068 -19.949922)
			(size 0.4572 0.4572)
			(layers "F.Cu" "F.Mask" "F.Paste")
			(net "P5E_PEX0_STN5_RX_DP<92>")
		)
		(pad "D37" smd circle
			(at 11.400028 -19.949922)
			(size 0.4572 0.4572)
			(layers "F.Cu" "F.Mask" "F.Paste")
			(net "GND")
		)
		(pad "D38" smd circle
			(at 12.349988 -19.949922)
			(size 0.4572 0.4572)
			(layers "F.Cu" "F.Mask" "F.Paste")
			(net "P5E_PEX0_STN5_RX_DP<94>")
		)
		(pad "D39" smd circle
			(at 13.299948 -19.949922)
			(size 0.4572 0.4572)
			(layers "F.Cu" "F.Mask" "F.Paste")
			(net "GND")
		)
		(pad "D40" smd circle
			(at 14.249908 -19.949922)
			(size 0.4572 0.4572)
			(layers "F.Cu" "F.Mask" "F.Paste")
			(net "P5E_PEX0_STN4_RX_DP<79>")
		)
		(pad "D41" smd circle
			(at 15.200122 -19.949922)
			(size 0.4572 0.4572)
			(layers "F.Cu" "F.Mask" "F.Paste")
			(net "GND")
		)
		(pad "D42" smd circle
			(at 16.150082 -19.949922)
			(size 0.4572 0.4572)
			(layers "F.Cu" "F.Mask" "F.Paste")
			(net "P5E_PEX0_STN4_RX_DP<77>")
		)
		(pad "D43" smd circle
			(at 17.100042 -19.949922)
			(size 0.4572 0.4572)
			(layers "F.Cu" "F.Mask" "F.Paste")
			(net "GND")
		)
		(pad "D44" smd circle
			(at 18.050002 -19.949922)
			(size 0.4572 0.4572)
			(layers "F.Cu" "F.Mask" "F.Paste")
			(net "P5E_PEX0_STN4_RX_DP<75>")
		)
		(pad "D45" smd circle
			(at 18.999962 -19.949922)
			(size 0.4572 0.4572)
			(layers "F.Cu" "F.Mask" "F.Paste")
			(net "GND")
		)
		(pad "D46" smd circle
			(at 19.949922 -19.949922)
			(size 0.4572 0.4572)
			(layers "F.Cu" "F.Mask" "F.Paste")
			(net "P5E_PEX0_STN4_RX_DP<73>")
		)
		(pad "D47" smd circle
			(at 20.899882 -19.949922)
			(size 0.4572 0.4572)
			(layers "F.Cu" "F.Mask" "F.Paste")
			(net "GND")
		)
		(pad "D48" smd circle
			(at 21.850096 -19.949922)
			(size 0.4572 0.4572)
			(layers "F.Cu" "F.Mask" "F.Paste")
			(net "GND")
		)
		(pad "D49" smd circle
			(at 22.800056 -19.949922)
			(size 0.4572 0.4572)
			(layers "F.Cu" "F.Mask" "F.Paste")
			(net "GND")
		)
		(pad "E1" smd circle
			(at -22.800056 -18.999962)
			(size 0.4572 0.4572)
			(layers "F.Cu" "F.Mask" "F.Paste")
			(net "P5E_PEX0_STN7_TX_DN<122>")
		)
		(pad "E2" smd circle
			(at -21.850096 -18.999962)
			(size 0.4572 0.4572)
			(layers "F.Cu" "F.Mask" "F.Paste")
			(net "P5E_PEX0_STN7_TX_DP<122>")
		)
		(pad "E3" smd circle
			(at -20.899882 -18.999962)
			(size 0.4572 0.4572)
			(layers "F.Cu" "F.Mask" "F.Paste")
			(net "GND")
		)
		(pad "E4" smd circle
			(at -19.949922 -18.999962)
			(size 0.4572 0.4572)
			(layers "F.Cu" "F.Mask" "F.Paste")
			(net "GND")
		)
		(pad "E5" smd circle
			(at -18.999962 -18.999962)
			(size 0.4572 0.4572)
			(layers "F.Cu" "F.Mask" "F.Paste")
			(net "GND")
		)
		(pad "E6" smd circle
			(at -18.050002 -18.999962)
			(size 0.4572 0.4572)
			(layers "F.Cu" "F.Mask" "F.Paste")
			(net "GND")
		)
		(pad "E7" smd circle
			(at -17.100042 -18.999962)
			(size 0.4572 0.4572)
			(layers "F.Cu" "F.Mask" "F.Paste")
			(net "GND")
		)
		(pad "E8" smd circle
			(at -16.150082 -18.999962)
			(size 0.4572 0.4572)
			(layers "F.Cu" "F.Mask" "F.Paste")
			(net "GND")
		)
		(pad "E9" smd circle
			(at -15.200122 -18.999962)
			(size 0.4572 0.4572)
			(layers "F.Cu" "F.Mask" "F.Paste")
			(net "GND")
		)
		(pad "E10" smd circle
			(at -14.249908 -18.999962)
			(size 0.4572 0.4572)
			(layers "F.Cu" "F.Mask" "F.Paste")
			(net "GND")
		)
		(pad "E11" smd circle
			(at -13.299948 -18.999962)
			(size 0.4572 0.4572)
			(layers "F.Cu" "F.Mask" "F.Paste")
			(net "GND")
		)
		(pad "E12" smd circle
			(at -12.349988 -18.999962)
			(size 0.4572 0.4572)
			(layers "F.Cu" "F.Mask" "F.Paste")
			(net "GND")
		)
		(pad "E13" smd circle
			(at -11.400028 -18.999962)
			(size 0.4572 0.4572)
			(layers "F.Cu" "F.Mask" "F.Paste")
			(net "GND")
		)
		(pad "E14" smd circle
			(at -10.450068 -18.999962)
			(size 0.4572 0.4572)
			(layers "F.Cu" "F.Mask" "F.Paste")
			(net "GND")
		)
		(pad "E15" smd circle
			(at -9.500108 -18.999962)
			(size 0.4572 0.4572)
			(layers "F.Cu" "F.Mask" "F.Paste")
			(net "GND")
		)
		(pad "E16" smd circle
			(at -8.549894 -18.999962)
			(size 0.4572 0.4572)
			(layers "F.Cu" "F.Mask" "F.Paste")
			(net "GND")
		)
		(pad "E17" smd circle
			(at -7.599934 -18.999962)
			(size 0.4572 0.4572)
			(layers "F.Cu" "F.Mask" "F.Paste")
			(net "GND")
		)
		(pad "E18" smd circle
			(at -6.649974 -18.999962)
			(size 0.4572 0.4572)
			(layers "F.Cu" "F.Mask" "F.Paste")
			(net "GND")
		)
		(pad "E19" smd circle
			(at -5.700014 -18.999962)
			(size 0.4572 0.4572)
			(layers "F.Cu" "F.Mask" "F.Paste")
			(net "GND")
		)
		(pad "E20" smd circle
			(at -4.750054 -18.999962)
			(size 0.4572 0.4572)
			(layers "F.Cu" "F.Mask" "F.Paste")
			(net "GND")
		)
		(pad "E21" smd circle
			(at -3.800094 -18.999962)
			(size 0.4572 0.4572)
			(layers "F.Cu" "F.Mask" "F.Paste")
			(net "GND")
		)
		(pad "E22" smd circle
			(at -2.84988 -18.999962)
			(size 0.4572 0.4572)
			(layers "F.Cu" "F.Mask" "F.Paste")
			(net "GND")
		)
		(pad "E23" smd circle
			(at -1.89992 -18.999962)
			(size 0.4572 0.4572)
			(layers "F.Cu" "F.Mask" "F.Paste")
			(net "GND")
		)
		(pad "E24" smd circle
			(at -0.94996 -18.999962)
			(size 0.4572 0.4572)
			(layers "F.Cu" "F.Mask" "F.Paste")
			(net "GND")
		)
		(pad "E25" smd circle
			(at 0 -18.999962)
			(size 0.4572 0.4572)
			(layers "F.Cu" "F.Mask" "F.Paste")
			(net "GND")
		)
		(pad "E26" smd circle
			(at 0.94996 -18.999962)
			(size 0.4572 0.4572)
			(layers "F.Cu" "F.Mask" "F.Paste")
			(net "GND")
		)
		(pad "E27" smd circle
			(at 1.89992 -18.999962)
			(size 0.4572 0.4572)
			(layers "F.Cu" "F.Mask" "F.Paste")
			(net "GND")
		)
		(pad "E28" smd circle
			(at 2.84988 -18.999962)
			(size 0.4572 0.4572)
			(layers "F.Cu" "F.Mask" "F.Paste")
			(net "GND")
		)
		(pad "E29" smd circle
			(at 3.800094 -18.999962)
			(size 0.4572 0.4572)
			(layers "F.Cu" "F.Mask" "F.Paste")
			(net "GND")
		)
		(pad "E30" smd circle
			(at 4.750054 -18.999962)
			(size 0.4572 0.4572)
			(layers "F.Cu" "F.Mask" "F.Paste")
			(net "GND")
		)
		(pad "E31" smd circle
			(at 5.700014 -18.999962)
			(size 0.4572 0.4572)
			(layers "F.Cu" "F.Mask" "F.Paste")
			(net "GND")
		)
		(pad "E32" smd circle
			(at 6.649974 -18.999962)
			(size 0.4572 0.4572)
			(layers "F.Cu" "F.Mask" "F.Paste")
			(net "GND")
		)
		(pad "E33" smd circle
			(at 7.599934 -18.999962)
			(size 0.4572 0.4572)
			(layers "F.Cu" "F.Mask" "F.Paste")
			(net "GND")
		)
		(pad "E34" smd circle
			(at 8.549894 -18.999962)
			(size 0.4572 0.4572)
			(layers "F.Cu" "F.Mask" "F.Paste")
			(net "GND")
		)
		(pad "E35" smd circle
			(at 9.500108 -18.999962)
			(size 0.4572 0.4572)
			(layers "F.Cu" "F.Mask" "F.Paste")
			(net "GND")
		)
		(pad "E36" smd circle
			(at 10.450068 -18.999962)
			(size 0.4572 0.4572)
			(layers "F.Cu" "F.Mask" "F.Paste")
			(net "GND")
		)
		(pad "E37" smd circle
			(at 11.400028 -18.999962)
			(size 0.4572 0.4572)
			(layers "F.Cu" "F.Mask" "F.Paste")
			(net "GND")
		)
		(pad "E38" smd circle
			(at 12.349988 -18.999962)
			(size 0.4572 0.4572)
			(layers "F.Cu" "F.Mask" "F.Paste")
			(net "GND")
		)
	)
)
